(kicad_pcb
	(version 20260206)
	(generator "pcbnew")
	(generator_version "10.0")
	(general
		(thickness 1.6)
		(legacy_teardrops no)
	)
	(paper "A4")
	(title_block
		(title "01162023_DA0F0TEBIF0_F0T_Expander_BD_F_brd_V02_OCP.brd")
		(comment 1 "Grand Teton / footprint 5622 of 9728 (PEX2), pads 2238-2358 of 2397")
	)
	(layers
		(0 "F.Cu" signal "TOP")
		(4 "In1.Cu" signal "GND")
		(6 "In2.Cu" signal "VCC")
		(8 "In3.Cu" signal "VCC1")
		(10 "In4.Cu" signal "GND1")
		(12 "In5.Cu" signal "IN1")
		(14 "In6.Cu" signal "GND2")
		(16 "In7.Cu" signal "IN2")
		(18 "In8.Cu" signal "GND3")
		(20 "In9.Cu" signal "IN3")
		(22 "In10.Cu" signal "GND4")
		(24 "In11.Cu" signal "IN4")
		(26 "In12.Cu" signal "GND5")
		(28 "In13.Cu" signal "IN5")
		(30 "In14.Cu" signal "GND6")
		(32 "In15.Cu" signal "IN6")
		(34 "In16.Cu" signal "GND7")
		(2 "B.Cu" signal "BOTTOM")
		(9 "F.Adhes" user "F.Adhesive")
		(11 "B.Adhes" user "B.Adhesive")
		(13 "F.Paste" user "Package Geometry/Pastemask Top")
		(15 "B.Paste" user "Package Geometry/Pastemask Bottom")
		(5 "F.SilkS" user "Ref Des/Silkscreen Top")
		(7 "B.SilkS" user "Ref Des/Silkscreen Bottom")
		(1 "F.Mask" user "Board Geometry/Soldermask Top")
		(3 "B.Mask" user "Board Geometry/Soldermask Bottom")
		(17 "Dwgs.User" user "User.Drawings")
		(19 "Cmts.User" user "User.Comments")
		(21 "Eco1.User" user "User.Eco1")
		(23 "Eco2.User" user "User.Eco2")
		(25 "Edge.Cuts" user "Board Geometry/Outline")
		(27 "Margin" user)
		(31 "F.CrtYd" user "Package Geometry/Place Bound Top")
		(29 "B.CrtYd" user "Package Geometry/Place Bound Bottom")
		(35 "F.Fab" user "Ref Des/Assembly Top")
		(33 "B.Fab" user "Ref Des/Assembly Bottom")
	)
	(footprint ""
		(layer "F.Cu")
		(at 291.84981 -295.89984)
		(property "Reference" "PEX2"
			(at -3.35153 35.56762 0)
			(unlocked yes)
			(layer "F.SilkS")
			(effects
				(font
					(size 2.032 1.524)
					(thickness 0.1524)
				)
				(justify left)
			)
		)
		(property "Value" ""
			(at 0 0 0)
			(layer "F.Fab")
			(effects
				(font
					(size 1.27 1.27)
				)
			)
		)
		(duplicate_pad_numbers_are_jumpers no)
		(pad "U37" smd circle
			(at 11.400028 -7.599934)
			(size 0.4572 0.4572)
			(layers "F.Cu" "F.Mask" "F.Paste")
			(net "GND")
		)
		(pad "U38" smd circle
			(at 12.349988 -7.599934)
			(size 0.4572 0.4572)
			(layers "F.Cu" "F.Mask" "F.Paste")
			(net "Net_5321")
		)
		(pad "U39" smd circle
			(at 13.299948 -7.599934)
			(size 0.4572 0.4572)
			(layers "F.Cu" "F.Mask" "F.Paste")
			(net "Net_5315")
		)
		(pad "U40" smd circle
			(at 14.249908 -7.599934)
			(size 0.4572 0.4572)
			(layers "F.Cu" "F.Mask" "F.Paste")
			(net "GND")
		)
		(pad "U41" smd circle
			(at 15.200122 -7.599934)
			(size 0.4572 0.4572)
			(layers "F.Cu" "F.Mask" "F.Paste")
			(net "GND")
		)
		(pad "U42" smd circle
			(at 16.150082 -7.599934)
			(size 0.4572 0.4572)
			(layers "F.Cu" "F.Mask" "F.Paste")
			(net "GND")
		)
		(pad "U43" smd circle
			(at 17.100042 -7.599934)
			(size 0.4572 0.4572)
			(layers "F.Cu" "F.Mask" "F.Paste")
			(net "Net_1697")
		)
		(pad "U44" smd circle
			(at 18.050002 -7.599934)
			(size 0.4572 0.4572)
			(layers "F.Cu" "F.Mask" "F.Paste")
			(net "Net_1687")
		)
		(pad "U45" smd circle
			(at 18.999962 -7.599934)
			(size 0.4572 0.4572)
			(layers "F.Cu" "F.Mask" "F.Paste")
			(net "GND")
		)
		(pad "U46" smd circle
			(at 19.949922 -7.599934)
			(size 0.4572 0.4572)
			(layers "F.Cu" "F.Mask" "F.Paste")
			(net "Net_1577")
		)
		(pad "U47" smd circle
			(at 20.899882 -7.599934)
			(size 0.4572 0.4572)
			(layers "F.Cu" "F.Mask" "F.Paste")
			(net "Net_1572")
		)
		(pad "U48" smd circle
			(at 21.850096 -7.599934)
			(size 0.4572 0.4572)
			(layers "F.Cu" "F.Mask" "F.Paste")
			(net "GND")
		)
		(pad "U49" smd circle
			(at 22.800056 -7.599934)
			(size 0.4572 0.4572)
			(layers "F.Cu" "F.Mask" "F.Paste")
			(net "GND")
		)
		(pad "V1" smd circle
			(at -22.800056 -6.649974)
			(size 0.4572 0.4572)
			(layers "F.Cu" "F.Mask" "F.Paste")
			(net "P5E_PEX2_STN7_RX_DN<113>")
		)
		(pad "V2" smd circle
			(at -21.850096 -6.649974)
			(size 0.4572 0.4572)
			(layers "F.Cu" "F.Mask" "F.Paste")
			(net "P5E_PEX2_STN7_RX_DP<113>")
		)
		(pad "V3" smd circle
			(at -20.899882 -6.649974)
			(size 0.4572 0.4572)
			(layers "F.Cu" "F.Mask" "F.Paste")
			(net "GND")
		)
		(pad "V4" smd circle
			(at -19.949922 -6.649974)
			(size 0.4572 0.4572)
			(layers "F.Cu" "F.Mask" "F.Paste")
			(net "GND")
		)
		(pad "V5" smd circle
			(at -18.999962 -6.649974)
			(size 0.4572 0.4572)
			(layers "F.Cu" "F.Mask" "F.Paste")
			(net "GND")
		)
		(pad "V6" smd circle
			(at -18.050002 -6.649974)
			(size 0.4572 0.4572)
			(layers "F.Cu" "F.Mask" "F.Paste")
			(net "GND")
		)
		(pad "V7" smd circle
			(at -17.100042 -6.649974)
			(size 0.4572 0.4572)
			(layers "F.Cu" "F.Mask" "F.Paste")
			(net "GND")
		)
		(pad "V8" smd circle
			(at -16.150082 -6.649974)
			(size 0.4572 0.4572)
			(layers "F.Cu" "F.Mask" "F.Paste")
			(net "P5E_PEX2_STN7_TX_DN<113>")
		)
		(pad "V9" smd circle
			(at -15.200122 -6.649974)
			(size 0.4572 0.4572)
			(layers "F.Cu" "F.Mask" "F.Paste")
			(net "P5E_PEX2_STN7_TX_DP<113>")
		)
		(pad "V10" smd circle
			(at -14.249908 -6.649974)
			(size 0.4572 0.4572)
			(layers "F.Cu" "F.Mask" "F.Paste")
			(net "GND")
		)
		(pad "V11" smd circle
			(at -13.299948 -6.649974)
			(size 0.4572 0.4572)
			(layers "F.Cu" "F.Mask" "F.Paste")
			(net "GND")
		)
		(pad "V12" smd circle
			(at -12.349988 -6.649974)
			(size 0.4572 0.4572)
			(layers "F.Cu" "F.Mask" "F.Paste")
			(net "GND")
		)
		(pad "V13" smd circle
			(at -11.400028 -6.649974)
			(size 0.4572 0.4572)
			(layers "F.Cu" "F.Mask" "F.Paste")
			(net "GND")
		)
		(pad "V14" smd circle
			(at -10.450068 -6.649974)
			(size 0.4572 0.4572)
			(layers "F.Cu" "F.Mask" "F.Paste")
			(net "P1V8_VDDA_PEX2")
		)
		(pad "V15" smd circle
			(at -9.500108 -6.649974)
			(size 0.4572 0.4572)
			(layers "F.Cu" "F.Mask" "F.Paste")
			(net "GND")
		)
		(pad "V16" smd circle
			(at -8.549894 -6.649974)
			(size 0.4572 0.4572)
			(layers "F.Cu" "F.Mask" "F.Paste")
			(net "P1V25_PEX2")
		)
		(pad "V17" smd circle
			(at -7.599934 -6.649974)
			(size 0.4572 0.4572)
			(layers "F.Cu" "F.Mask" "F.Paste")
			(net "P1V25_PEX2")
		)
		(pad "V18" smd circle
			(at -6.649974 -6.649974)
			(size 0.4572 0.4572)
			(layers "F.Cu" "F.Mask" "F.Paste")
			(net "P1V25_PEX2")
		)
		(pad "V19" smd circle
			(at -5.700014 -6.649974)
			(size 0.4572 0.4572)
			(layers "F.Cu" "F.Mask" "F.Paste")
			(net "P1V25_PEX2")
		)
		(pad "V20" smd circle
			(at -4.750054 -6.649974)
			(size 0.4572 0.4572)
			(layers "F.Cu" "F.Mask" "F.Paste")
			(net "P1V25_PEX2")
		)
		(pad "V21" smd circle
			(at -3.800094 -6.649974)
			(size 0.4572 0.4572)
			(layers "F.Cu" "F.Mask" "F.Paste")
			(net "P1V25_PEX2")
		)
		(pad "V22" smd circle
			(at -2.84988 -6.649974)
			(size 0.4572 0.4572)
			(layers "F.Cu" "F.Mask" "F.Paste")
			(net "P1V25_PEX2")
		)
		(pad "V23" smd circle
			(at -1.89992 -6.649974)
			(size 0.4572 0.4572)
			(layers "F.Cu" "F.Mask" "F.Paste")
			(net "P1V25_PEX2")
		)
		(pad "V24" smd circle
			(at -0.94996 -6.649974)
			(size 0.4572 0.4572)
			(layers "F.Cu" "F.Mask" "F.Paste")
			(net "P1V25_PEX2")
		)
		(pad "V25" smd circle
			(at 0 -6.649974)
			(size 0.4572 0.4572)
			(layers "F.Cu" "F.Mask" "F.Paste")
			(net "P1V25_PEX2")
		)
		(pad "V26" smd circle
			(at 0.94996 -6.649974)
			(size 0.4572 0.4572)
			(layers "F.Cu" "F.Mask" "F.Paste")
			(net "P1V25_PEX2")
		)
		(pad "V27" smd circle
			(at 1.89992 -6.649974)
			(size 0.4572 0.4572)
			(layers "F.Cu" "F.Mask" "F.Paste")
			(net "P1V25_PEX2")
		)
		(pad "V28" smd circle
			(at 2.84988 -6.649974)
			(size 0.4572 0.4572)
			(layers "F.Cu" "F.Mask" "F.Paste")
			(net "P1V25_PEX2")
		)
		(pad "V29" smd circle
			(at 3.800094 -6.649974)
			(size 0.4572 0.4572)
			(layers "F.Cu" "F.Mask" "F.Paste")
			(net "P1V25_PEX2")
		)
		(pad "V30" smd circle
			(at 4.750054 -6.649974)
			(size 0.4572 0.4572)
			(layers "F.Cu" "F.Mask" "F.Paste")
			(net "P1V25_PEX2")
		)
		(pad "V31" smd circle
			(at 5.700014 -6.649974)
			(size 0.4572 0.4572)
			(layers "F.Cu" "F.Mask" "F.Paste")
			(net "P1V25_PEX2")
		)
		(pad "V32" smd circle
			(at 6.649974 -6.649974)
			(size 0.4572 0.4572)
			(layers "F.Cu" "F.Mask" "F.Paste")
			(net "P1V25_PEX2")
		)
		(pad "V33" smd circle
			(at 7.599934 -6.649974)
			(size 0.4572 0.4572)
			(layers "F.Cu" "F.Mask" "F.Paste")
			(net "P1V25_PEX2")
		)
		(pad "V34" smd circle
			(at 8.549894 -6.649974)
			(size 0.4572 0.4572)
			(layers "F.Cu" "F.Mask" "F.Paste")
			(net "GND")
		)
		(pad "V35" smd circle
			(at 9.500108 -6.649974)
			(size 0.4572 0.4572)
			(layers "F.Cu" "F.Mask" "F.Paste")
			(net "P1V8_PEX")
		)
		(pad "V36" smd circle
			(at 10.450068 -6.649974)
			(size 0.4572 0.4572)
			(layers "F.Cu" "F.Mask" "F.Paste")
			(net "GND")
		)
		(pad "V37" smd circle
			(at 11.400028 -6.649974)
			(size 0.4572 0.4572)
			(layers "F.Cu" "F.Mask" "F.Paste")
			(net "GND")
		)
		(pad "V38" smd circle
			(at 12.349988 -6.649974)
			(size 0.4572 0.4572)
			(layers "F.Cu" "F.Mask" "F.Paste")
			(net "GND")
		)
		(pad "V39" smd circle
			(at 13.299948 -6.649974)
			(size 0.4572 0.4572)
			(layers "F.Cu" "F.Mask" "F.Paste")
			(net "VSENSE_P0V8_PEX2_SKT_VSEN")
		)
		(pad "V40" smd circle
			(at 14.249908 -6.649974)
			(size 0.4572 0.4572)
			(layers "F.Cu" "F.Mask" "F.Paste")
			(net "GND")
		)
		(pad "V41" smd circle
			(at 15.200122 -6.649974)
			(size 0.4572 0.4572)
			(layers "F.Cu" "F.Mask" "F.Paste")
			(net "Net_1663")
		)
		(pad "V42" smd circle
			(at 16.150082 -6.649974)
			(size 0.4572 0.4572)
			(layers "F.Cu" "F.Mask" "F.Paste")
			(net "Net_1661")
		)
		(pad "V43" smd circle
			(at 17.100042 -6.649974)
			(size 0.4572 0.4572)
			(layers "F.Cu" "F.Mask" "F.Paste")
			(net "GND")
		)
		(pad "V44" smd circle
			(at 18.050002 -6.649974)
			(size 0.4572 0.4572)
			(layers "F.Cu" "F.Mask" "F.Paste")
			(net "GND")
		)
		(pad "V45" smd circle
			(at 18.999962 -6.649974)
			(size 0.4572 0.4572)
			(layers "F.Cu" "F.Mask" "F.Paste")
			(net "GND")
		)
		(pad "V46" smd circle
			(at 19.949922 -6.649974)
			(size 0.4572 0.4572)
			(layers "F.Cu" "F.Mask" "F.Paste")
			(net "GND")
		)
		(pad "V47" smd circle
			(at 20.899882 -6.649974)
			(size 0.4572 0.4572)
			(layers "F.Cu" "F.Mask" "F.Paste")
			(net "GND")
		)
		(pad "V48" smd circle
			(at 21.850096 -6.649974)
			(size 0.4572 0.4572)
			(layers "F.Cu" "F.Mask" "F.Paste")
			(net "Net_1582")
		)
		(pad "V49" smd circle
			(at 22.800056 -6.649974)
			(size 0.4572 0.4572)
			(layers "F.Cu" "F.Mask" "F.Paste")
			(net "Net_1585")
		)
		(pad "W1" smd circle
			(at -22.800056 -5.700014)
			(size 0.4572 0.4572)
			(layers "F.Cu" "F.Mask" "F.Paste")
			(net "GND")
		)
		(pad "W2" smd circle
			(at -21.850096 -5.700014)
			(size 0.4572 0.4572)
			(layers "F.Cu" "F.Mask" "F.Paste")
			(net "GND")
		)
		(pad "W3" smd circle
			(at -20.899882 -5.700014)
			(size 0.4572 0.4572)
			(layers "F.Cu" "F.Mask" "F.Paste")
			(net "P5E_PEX2_STN7_RX_DN<112>")
		)
		(pad "W4" smd circle
			(at -19.949922 -5.700014)
			(size 0.4572 0.4572)
			(layers "F.Cu" "F.Mask" "F.Paste")
			(net "P5E_PEX2_STN7_RX_DP<112>")
		)
		(pad "W5" smd circle
			(at -18.999962 -5.700014)
			(size 0.4572 0.4572)
			(layers "F.Cu" "F.Mask" "F.Paste")
			(net "GND")
		)
		(pad "W6" smd circle
			(at -18.050002 -5.700014)
			(size 0.4572 0.4572)
			(layers "F.Cu" "F.Mask" "F.Paste")
			(net "P5E_PEX2_STN7_TX_DN<112>")
		)
		(pad "W7" smd circle
			(at -17.100042 -5.700014)
			(size 0.4572 0.4572)
			(layers "F.Cu" "F.Mask" "F.Paste")
			(net "P5E_PEX2_STN7_TX_DP<112>")
		)
		(pad "W8" smd circle
			(at -16.150082 -5.700014)
			(size 0.4572 0.4572)
			(layers "F.Cu" "F.Mask" "F.Paste")
			(net "GND")
		)
		(pad "W9" smd circle
			(at -15.200122 -5.700014)
			(size 0.4572 0.4572)
			(layers "F.Cu" "F.Mask" "F.Paste")
			(net "GND")
		)
		(pad "W10" smd circle
			(at -14.249908 -5.700014)
			(size 0.4572 0.4572)
			(layers "F.Cu" "F.Mask" "F.Paste")
			(net "GND")
		)
		(pad "W11" smd circle
			(at -13.299948 -5.700014)
			(size 0.4572 0.4572)
			(layers "F.Cu" "F.Mask" "F.Paste")
			(net "GND")
		)
		(pad "W12" smd circle
			(at -12.349988 -5.700014)
			(size 0.4572 0.4572)
			(layers "F.Cu" "F.Mask" "F.Paste")
			(net "GND")
		)
		(pad "W13" smd circle
			(at -11.400028 -5.700014)
			(size 0.4572 0.4572)
			(layers "F.Cu" "F.Mask" "F.Paste")
			(net "GND")
		)
		(pad "W14" smd circle
			(at -10.450068 -5.700014)
			(size 0.4572 0.4572)
			(layers "F.Cu" "F.Mask" "F.Paste")
			(net "GND")
		)
		(pad "W15" smd circle
			(at -9.500108 -5.700014)
			(size 0.4572 0.4572)
			(layers "F.Cu" "F.Mask" "F.Paste")
			(net "GND")
		)
		(pad "W16" smd circle
			(at -8.549894 -5.700014)
			(size 0.4572 0.4572)
			(layers "F.Cu" "F.Mask" "F.Paste")
			(net "GND")
		)
		(pad "W17" smd circle
			(at -7.599934 -5.700014)
			(size 0.4572 0.4572)
			(layers "F.Cu" "F.Mask" "F.Paste")
			(net "GND")
		)
		(pad "W18" smd circle
			(at -6.649974 -5.700014)
			(size 0.4572 0.4572)
			(layers "F.Cu" "F.Mask" "F.Paste")
			(net "GND")
		)
		(pad "W19" smd circle
			(at -5.700014 -5.700014)
			(size 0.4572 0.4572)
			(layers "F.Cu" "F.Mask" "F.Paste")
			(net "GND")
		)
		(pad "W20" smd circle
			(at -4.750054 -5.700014)
			(size 0.4572 0.4572)
			(layers "F.Cu" "F.Mask" "F.Paste")
			(net "GND")
		)
		(pad "W21" smd circle
			(at -3.800094 -5.700014)
			(size 0.4572 0.4572)
			(layers "F.Cu" "F.Mask" "F.Paste")
			(net "GND")
		)
		(pad "W22" smd circle
			(at -2.84988 -5.700014)
			(size 0.4572 0.4572)
			(layers "F.Cu" "F.Mask" "F.Paste")
			(net "GND")
		)
		(pad "W23" smd circle
			(at -1.89992 -5.700014)
			(size 0.4572 0.4572)
			(layers "F.Cu" "F.Mask" "F.Paste")
			(net "GND")
		)
		(pad "W24" smd circle
			(at -0.94996 -5.700014)
			(size 0.4572 0.4572)
			(layers "F.Cu" "F.Mask" "F.Paste")
			(net "GND")
		)
		(pad "W25" smd circle
			(at 0 -5.700014)
			(size 0.4572 0.4572)
			(layers "F.Cu" "F.Mask" "F.Paste")
			(net "GND")
		)
		(pad "W26" smd circle
			(at 0.94996 -5.700014)
			(size 0.4572 0.4572)
			(layers "F.Cu" "F.Mask" "F.Paste")
			(net "GND")
		)
		(pad "W27" smd circle
			(at 1.89992 -5.700014)
			(size 0.4572 0.4572)
			(layers "F.Cu" "F.Mask" "F.Paste")
			(net "GND")
		)
		(pad "W28" smd circle
			(at 2.84988 -5.700014)
			(size 0.4572 0.4572)
			(layers "F.Cu" "F.Mask" "F.Paste")
			(net "GND")
		)
		(pad "W29" smd circle
			(at 3.800094 -5.700014)
			(size 0.4572 0.4572)
			(layers "F.Cu" "F.Mask" "F.Paste")
			(net "GND")
		)
		(pad "W30" smd circle
			(at 4.750054 -5.700014)
			(size 0.4572 0.4572)
			(layers "F.Cu" "F.Mask" "F.Paste")
			(net "GND")
		)
		(pad "W31" smd circle
			(at 5.700014 -5.700014)
			(size 0.4572 0.4572)
			(layers "F.Cu" "F.Mask" "F.Paste")
			(net "GND")
		)
		(pad "W32" smd circle
			(at 6.649974 -5.700014)
			(size 0.4572 0.4572)
			(layers "F.Cu" "F.Mask" "F.Paste")
			(net "GND")
		)
		(pad "W33" smd circle
			(at 7.599934 -5.700014)
			(size 0.4572 0.4572)
			(layers "F.Cu" "F.Mask" "F.Paste")
			(net "GND")
		)
		(pad "W34" smd circle
			(at 8.549894 -5.700014)
			(size 0.4572 0.4572)
			(layers "F.Cu" "F.Mask" "F.Paste")
			(net "GND")
		)
		(pad "W35" smd circle
			(at 9.500108 -5.700014)
			(size 0.4572 0.4572)
			(layers "F.Cu" "F.Mask" "F.Paste")
			(net "P1V8_PEX")
		)
		(pad "W36" smd circle
			(at 10.450068 -5.700014)
			(size 0.4572 0.4572)
			(layers "F.Cu" "F.Mask" "F.Paste")
			(net "GND")
		)
		(pad "W37" smd circle
			(at 11.400028 -5.700014)
			(size 0.4572 0.4572)
			(layers "F.Cu" "F.Mask" "F.Paste")
			(net "GND")
		)
		(pad "W38" smd circle
			(at 12.349988 -5.700014)
			(size 0.4572 0.4572)
			(layers "F.Cu" "F.Mask" "F.Paste")
			(net "GND")
		)
		(pad "W39" smd circle
			(at 13.299948 -5.700014)
			(size 0.4572 0.4572)
			(layers "F.Cu" "F.Mask" "F.Paste")
			(net "VSENSE_P0V8_PEX2_SKT_VRTN")
		)
		(pad "W40" smd circle
			(at 14.249908 -5.700014)
			(size 0.4572 0.4572)
			(layers "F.Cu" "F.Mask" "F.Paste")
			(net "GND")
		)
		(pad "W41" smd circle
			(at 15.200122 -5.700014)
			(size 0.4572 0.4572)
			(layers "F.Cu" "F.Mask" "F.Paste")
			(net "GND")
		)
		(pad "W42" smd circle
			(at 16.150082 -5.700014)
			(size 0.4572 0.4572)
			(layers "F.Cu" "F.Mask" "F.Paste")
			(net "GND")
		)
		(pad "W43" smd circle
			(at 17.100042 -5.700014)
			(size 0.4572 0.4572)
			(layers "F.Cu" "F.Mask" "F.Paste")
			(net "Net_1705")
		)
		(pad "W44" smd circle
			(at 18.050002 -5.700014)
			(size 0.4572 0.4572)
			(layers "F.Cu" "F.Mask" "F.Paste")
			(net "Net_1669")
		)
		(pad "W45" smd circle
			(at 18.999962 -5.700014)
			(size 0.4572 0.4572)
			(layers "F.Cu" "F.Mask" "F.Paste")
			(net "GND")
		)
		(pad "W46" smd circle
			(at 19.949922 -5.700014)
			(size 0.4572 0.4572)
			(layers "F.Cu" "F.Mask" "F.Paste")
			(net "Net_1589")
		)
		(pad "W47" smd circle
			(at 20.899882 -5.700014)
			(size 0.4572 0.4572)
			(layers "F.Cu" "F.Mask" "F.Paste")
			(net "Net_1575")
		)
		(pad "W48" smd circle
			(at 21.850096 -5.700014)
			(size 0.4572 0.4572)
			(layers "F.Cu" "F.Mask" "F.Paste")
			(net "GND")
		)
		(pad "W49" smd circle
			(at 22.800056 -5.700014)
			(size 0.4572 0.4572)
			(layers "F.Cu" "F.Mask" "F.Paste")
			(net "GND")
		)
		(pad "Y1" smd circle
			(at -22.800056 -4.750054)
			(size 0.4572 0.4572)
			(layers "F.Cu" "F.Mask" "F.Paste")
			(net "GND")
		)
		(pad "Y2" smd circle
			(at -21.850096 -4.750054)
			(size 0.4572 0.4572)
			(layers "F.Cu" "F.Mask" "F.Paste")
			(net "GND")
		)
		(pad "Y3" smd circle
			(at -20.899882 -4.750054)
			(size 0.4572 0.4572)
			(layers "F.Cu" "F.Mask" "F.Paste")
			(net "GND")
		)
		(pad "Y4" smd circle
			(at -19.949922 -4.750054)
			(size 0.4572 0.4572)
			(layers "F.Cu" "F.Mask" "F.Paste")
			(net "GND")
		)
		(pad "Y5" smd circle
			(at -18.999962 -4.750054)
			(size 0.4572 0.4572)
			(layers "F.Cu" "F.Mask" "F.Paste")
			(net "GND")
		)
		(pad "Y6" smd circle
			(at -18.050002 -4.750054)
			(size 0.4572 0.4572)
			(layers "F.Cu" "F.Mask" "F.Paste")
			(net "GND")
		)
		(pad "Y7" smd circle
			(at -17.100042 -4.750054)
			(size 0.4572 0.4572)
			(layers "F.Cu" "F.Mask" "F.Paste")
			(net "GND")
		)
		(pad "Y8" smd circle
			(at -16.150082 -4.750054)
			(size 0.4572 0.4572)
			(layers "F.Cu" "F.Mask" "F.Paste")
			(net "GND")
		)
		(pad "Y9" smd circle
			(at -15.200122 -4.750054)
			(size 0.4572 0.4572)
			(layers "F.Cu" "F.Mask" "F.Paste")
			(net "GND")
		)
		(pad "Y10" smd circle
			(at -14.249908 -4.750054)
			(size 0.4572 0.4572)
			(layers "F.Cu" "F.Mask" "F.Paste")
			(net "GND")
		)
	)
)
